(kicad_pcb
	(version 20260206)
	(generator "pcbnew")
	(generator_version "10.0")
	(general
		(thickness 1.6)
		(legacy_teardrops no)
	)
	(paper "A4")
	(title_block
		(title "04192023_DAF0TMB3IC0_F0TG_MB_C_brd_V02_OCP.brd")
		(comment 1 "Grand Teton / footprint 2783 of 8354 (U26), pads 5341-5450 of 6102")
	)
	(layers
		(0 "F.Cu" signal "TOP")
		(4 "In1.Cu" signal "GND")
		(6 "In2.Cu" signal "IN1")
		(8 "In3.Cu" signal "GND1")
		(10 "In4.Cu" signal "IN2")
		(12 "In5.Cu" signal "GND2")
		(14 "In6.Cu" signal "IN3")
		(16 "In7.Cu" signal "GND3")
		(18 "In8.Cu" signal "VCC")
		(20 "In9.Cu" signal "VCC1")
		(22 "In10.Cu" signal "GND4")
		(24 "In11.Cu" signal "IN4")
		(26 "In12.Cu" signal "GND5")
		(28 "In13.Cu" signal "IN5")
		(30 "In14.Cu" signal "GND6")
		(32 "In15.Cu" signal "IN6")
		(34 "In16.Cu" signal "GND7")
		(2 "B.Cu" signal "BOTTOM")
		(9 "F.Adhes" user "F.Adhesive")
		(11 "B.Adhes" user "B.Adhesive")
		(13 "F.Paste" user "Package Geometry/Pastemask Top")
		(15 "B.Paste" user "Package Geometry/Pastemask Bottom")
		(5 "F.SilkS" user "Ref Des/Silkscreen Top")
		(7 "B.SilkS" user "Ref Des/Silkscreen Bottom")
		(1 "F.Mask" user "Board Geometry/Soldermask Top")
		(3 "B.Mask" user "Board Geometry/Soldermask Bottom")
		(17 "Dwgs.User" user "User.Drawings")
		(19 "Cmts.User" user "User.Comments")
		(21 "Eco1.User" user "User.Eco1")
		(23 "Eco2.User" user "User.Eco2")
		(25 "Edge.Cuts" user "Board Geometry/Outline")
		(27 "Margin" user)
		(31 "F.CrtYd" user "Package Geometry/Place Bound Top")
		(29 "B.CrtYd" user "Package Geometry/Place Bound Bottom")
		(35 "F.Fab" user "Ref Des/Assembly Top")
		(33 "B.Fab" user "Ref Des/Assembly Bottom")
	)
	(footprint ""
		(layer "F.Cu")
		(at 111.927894 -258.880356 180)
		(property "Reference" "U26"
			(at -45.05579 -61.794136 0)
			(unlocked yes)
			(layer "F.SilkS")
			(effects
				(font
					(size 0.7874 0.5842)
					(thickness 0.1524)
				)
			)
		)
		(property "Value" ""
			(at 0 0 180)
			(layer "F.Fab")
			(effects
				(font
					(size 1.27 1.27)
				)
			)
		)
		(duplicate_pad_numbers_are_jumpers no)
		(pad "K32" smd circle
			(at -5.489956 -29.51988 180)
			(size 0.450088 0.450088)
			(layers "F.Cu" "F.Mask" "F.Paste")
			(net "GND")
		)
		(pad "K33" smd circle
			(at -4.549902 -29.51988 180)
			(size 0.450088 0.450088)
			(layers "F.Cu" "F.Mask" "F.Paste")
			(net "GND")
		)
		(pad "K34" smd circle
			(at -3.610102 -29.51988 180)
			(size 0.450088 0.450088)
			(layers "F.Cu" "F.Mask" "F.Paste")
			(net "GND")
		)
		(pad "K35" smd circle
			(at -2.670048 -29.51988 180)
			(size 0.450088 0.450088)
			(layers "F.Cu" "F.Mask" "F.Paste")
			(net "GMI_CPU1_G2_CPU0_G0_TX_DP<1>")
		)
		(pad "K36" smd circle
			(at -1.729994 -29.51988 180)
			(size 0.450088 0.450088)
			(layers "F.Cu" "F.Mask" "F.Paste")
			(net "GMI_CPU1_G2_CPU0_G0_TX_DN<1>")
		)
		(pad "K37" smd circle
			(at -0.78994 -29.51988 180)
			(size 0.450088 0.450088)
			(layers "F.Cu" "F.Mask" "F.Paste")
			(net "GND")
		)
		(pad "K39" smd circle
			(at 1.089914 -29.51988 180)
			(size 0.450088 0.450088)
			(layers "F.Cu" "F.Mask" "F.Paste")
			(net "GND")
		)
		(pad "K40" smd circle
			(at 2.029968 -29.51988 180)
			(size 0.450088 0.450088)
			(layers "F.Cu" "F.Mask" "F.Paste")
			(net "GMI_CPU0_G2_CPU1_G0_TX_DN<14>")
		)
		(pad "K41" smd circle
			(at 2.970022 -29.51988 180)
			(size 0.450088 0.450088)
			(layers "F.Cu" "F.Mask" "F.Paste")
			(net "GMI_CPU0_G2_CPU1_G0_TX_DP<14>")
		)
		(pad "K42" smd circle
			(at 3.910076 -29.51988 180)
			(size 0.450088 0.450088)
			(layers "F.Cu" "F.Mask" "F.Paste")
			(net "GND")
		)
		(pad "K43" smd circle
			(at 4.849876 -29.51988 180)
			(size 0.450088 0.450088)
			(layers "F.Cu" "F.Mask" "F.Paste")
			(net "GND")
		)
		(pad "K44" smd circle
			(at 5.78993 -29.51988 180)
			(size 0.450088 0.450088)
			(layers "F.Cu" "F.Mask" "F.Paste")
			(net "GND")
		)
		(pad "K45" smd circle
			(at 6.729984 -29.51988 180)
			(size 0.450088 0.450088)
			(layers "F.Cu" "F.Mask" "F.Paste")
			(net "GND")
		)
		(pad "K46" smd circle
			(at 7.670038 -29.51988 180)
			(size 0.450088 0.450088)
			(layers "F.Cu" "F.Mask" "F.Paste")
			(net "GND")
		)
		(pad "K47" smd circle
			(at 8.610092 -29.51988 180)
			(size 0.450088 0.450088)
			(layers "F.Cu" "F.Mask" "F.Paste")
			(net "GND")
		)
		(pad "K48" smd circle
			(at 9.549892 -29.51988 180)
			(size 0.450088 0.450088)
			(layers "F.Cu" "F.Mask" "F.Paste")
			(net "GND")
		)
		(pad "K49" smd circle
			(at 10.489946 -29.51988 180)
			(size 0.450088 0.450088)
			(layers "F.Cu" "F.Mask" "F.Paste")
			(net "GND")
		)
		(pad "K50" smd circle
			(at 11.43 -29.51988 180)
			(size 0.450088 0.450088)
			(layers "F.Cu" "F.Mask" "F.Paste")
			(net "GND")
		)
		(pad "K51" smd circle
			(at 12.370054 -29.51988 180)
			(size 0.450088 0.450088)
			(layers "F.Cu" "F.Mask" "F.Paste")
			(net "GND")
		)
		(pad "K52" smd circle
			(at 13.310108 -29.51988 180)
			(size 0.450088 0.450088)
			(layers "F.Cu" "F.Mask" "F.Paste")
			(net "GND")
		)
		(pad "K53" smd circle
			(at 14.249908 -29.51988 180)
			(size 0.450088 0.450088)
			(layers "F.Cu" "F.Mask" "F.Paste")
			(net "GND")
		)
		(pad "K54" smd circle
			(at 15.189962 -29.51988 180)
			(size 0.450088 0.450088)
			(layers "F.Cu" "F.Mask" "F.Paste")
			(net "PVDDIO_P1")
		)
		(pad "K55" smd circle
			(at 16.130016 -29.51988 180)
			(size 0.450088 0.450088)
			(layers "F.Cu" "F.Mask" "F.Paste")
			(net "M_C_CPU1_SA_DQ<5>")
		)
		(pad "K56" smd circle
			(at 17.07007 -29.51988 180)
			(size 0.450088 0.450088)
			(layers "F.Cu" "F.Mask" "F.Paste")
			(net "M_C_CPU1_SA_DQ<6>")
		)
		(pad "K57" smd circle
			(at 18.010124 -29.51988 180)
			(size 0.450088 0.450088)
			(layers "F.Cu" "F.Mask" "F.Paste")
			(net "GND")
		)
		(pad "K58" smd circle
			(at 18.949924 -29.51988 180)
			(size 0.450088 0.450088)
			(layers "F.Cu" "F.Mask" "F.Paste")
			(net "M_D_CPU1_SA_DQ<5>")
		)
		(pad "K59" smd circle
			(at 19.889978 -29.51988 180)
			(size 0.450088 0.450088)
			(layers "F.Cu" "F.Mask" "F.Paste")
			(net "GND")
		)
		(pad "K60" smd circle
			(at 20.830032 -29.51988 180)
			(size 0.450088 0.450088)
			(layers "F.Cu" "F.Mask" "F.Paste")
			(net "M_D_CPU1_SA_DQ<6>")
		)
		(pad "K61" smd circle
			(at 21.770086 -29.51988 180)
			(size 0.450088 0.450088)
			(layers "F.Cu" "F.Mask" "F.Paste")
			(net "GND")
		)
		(pad "K62" smd circle
			(at 22.709886 -29.51988 180)
			(size 0.450088 0.450088)
			(layers "F.Cu" "F.Mask" "F.Paste")
			(net "M_B_CPU1_SA_DQ<5>")
		)
		(pad "K63" smd circle
			(at 23.64994 -29.51988 180)
			(size 0.450088 0.450088)
			(layers "F.Cu" "F.Mask" "F.Paste")
			(net "M_B_CPU1_SA_DQ<6>")
		)
		(pad "K64" smd circle
			(at 24.589994 -29.51988 180)
			(size 0.450088 0.450088)
			(layers "F.Cu" "F.Mask" "F.Paste")
			(net "GND")
		)
		(pad "K65" smd circle
			(at 25.530048 -29.51988 180)
			(size 0.450088 0.450088)
			(layers "F.Cu" "F.Mask" "F.Paste")
			(net "M_F_CPU1_SA_DQ<5>")
		)
		(pad "K66" smd circle
			(at 26.470102 -29.51988 180)
			(size 0.450088 0.450088)
			(layers "F.Cu" "F.Mask" "F.Paste")
			(net "GND")
		)
		(pad "K67" smd circle
			(at 27.409902 -29.51988 180)
			(size 0.450088 0.450088)
			(layers "F.Cu" "F.Mask" "F.Paste")
			(net "M_F_CPU1_SA_DQ<6>")
		)
		(pad "K68" smd circle
			(at 28.349956 -29.51988 180)
			(size 0.450088 0.450088)
			(layers "F.Cu" "F.Mask" "F.Paste")
			(net "GND")
		)
		(pad "K69" smd circle
			(at 29.29001 -29.51988 180)
			(size 0.450088 0.450088)
			(layers "F.Cu" "F.Mask" "F.Paste")
			(net "M_E_CPU1_SA_DQ<5>")
		)
		(pad "K70" smd circle
			(at 30.230064 -29.51988 180)
			(size 0.450088 0.450088)
			(layers "F.Cu" "F.Mask" "F.Paste")
			(net "M_E_CPU1_SA_DQ<6>")
		)
		(pad "K71" smd circle
			(at 31.170118 -29.51988 180)
			(size 0.450088 0.450088)
			(layers "F.Cu" "F.Mask" "F.Paste")
			(net "GND")
		)
		(pad "K72" smd circle
			(at 32.109918 -29.51988 180)
			(size 0.450088 0.450088)
			(layers "F.Cu" "F.Mask" "F.Paste")
			(net "M_A_CPU1_SA_DQ<5>")
		)
		(pad "K73" smd circle
			(at 33.049972 -29.51988 180)
			(size 0.450088 0.450088)
			(layers "F.Cu" "F.Mask" "F.Paste")
			(net "GND")
		)
		(pad "K74" smd circle
			(at 33.990026 -29.51988 180)
			(size 0.450088 0.450088)
			(layers "F.Cu" "F.Mask" "F.Paste")
			(net "M_A_CPU1_SA_DQ<6>")
		)
		(pad "L1" smd circle
			(at -34.159952 -28.710128 180)
			(size 0.450088 0.450088)
			(layers "F.Cu" "F.Mask" "F.Paste")
			(net "GND")
		)
		(pad "L2" smd circle
			(at -33.219898 -28.710128 180)
			(size 0.450088 0.450088)
			(layers "F.Cu" "F.Mask" "F.Paste")
			(net "M_G_CPU1_SA_DQ<8>")
		)
		(pad "L3" smd circle
			(at -32.280098 -28.710128 180)
			(size 0.450088 0.450088)
			(layers "F.Cu" "F.Mask" "F.Paste")
			(net "M_G_CPU1_SA_DQ<7>")
		)
		(pad "L4" smd circle
			(at -31.340044 -28.710128 180)
			(size 0.450088 0.450088)
			(layers "F.Cu" "F.Mask" "F.Paste")
			(net "PVDDCR_SOC_P1")
		)
		(pad "L5" smd circle
			(at -30.39999 -28.710128 180)
			(size 0.450088 0.450088)
			(layers "F.Cu" "F.Mask" "F.Paste")
			(net "M_K_CPU1_SA_DQ<8>")
		)
		(pad "L6" smd circle
			(at -29.459936 -28.710128 180)
			(size 0.450088 0.450088)
			(layers "F.Cu" "F.Mask" "F.Paste")
			(net "GND")
		)
		(pad "L7" smd circle
			(at -28.519882 -28.710128 180)
			(size 0.450088 0.450088)
			(layers "F.Cu" "F.Mask" "F.Paste")
			(net "M_K_CPU1_SA_DQ<7>")
		)
		(pad "L8" smd circle
			(at -27.580082 -28.710128 180)
			(size 0.450088 0.450088)
			(layers "F.Cu" "F.Mask" "F.Paste")
			(net "GND")
		)
		(pad "L9" smd circle
			(at -26.640028 -28.710128 180)
			(size 0.450088 0.450088)
			(layers "F.Cu" "F.Mask" "F.Paste")
			(net "M_L_CPU1_SA_DQ<8>")
		)
		(pad "L10" smd circle
			(at -25.699974 -28.710128 180)
			(size 0.450088 0.450088)
			(layers "F.Cu" "F.Mask" "F.Paste")
			(net "M_L_CPU1_SA_DQ<7>")
		)
		(pad "L11" smd circle
			(at -24.75992 -28.710128 180)
			(size 0.450088 0.450088)
			(layers "F.Cu" "F.Mask" "F.Paste")
			(net "PVDDCR_SOC_P1")
		)
		(pad "L12" smd circle
			(at -23.82012 -28.710128 180)
			(size 0.450088 0.450088)
			(layers "F.Cu" "F.Mask" "F.Paste")
			(net "M_H_CPU1_SA_DQ<8>")
		)
		(pad "L13" smd circle
			(at -22.880066 -28.710128 180)
			(size 0.450088 0.450088)
			(layers "F.Cu" "F.Mask" "F.Paste")
			(net "GND")
		)
		(pad "L14" smd circle
			(at -21.940012 -28.710128 180)
			(size 0.450088 0.450088)
			(layers "F.Cu" "F.Mask" "F.Paste")
			(net "M_H_CPU1_SA_DQ<7>")
		)
		(pad "L15" smd circle
			(at -20.999958 -28.710128 180)
			(size 0.450088 0.450088)
			(layers "F.Cu" "F.Mask" "F.Paste")
			(net "GND")
		)
		(pad "L16" smd circle
			(at -20.059904 -28.710128 180)
			(size 0.450088 0.450088)
			(layers "F.Cu" "F.Mask" "F.Paste")
			(net "M_J_CPU1_SA_DQ<8>")
		)
		(pad "L17" smd circle
			(at -19.120104 -28.710128 180)
			(size 0.450088 0.450088)
			(layers "F.Cu" "F.Mask" "F.Paste")
			(net "M_J_CPU1_SA_DQ<7>")
		)
		(pad "L18" smd circle
			(at -18.18005 -28.710128 180)
			(size 0.450088 0.450088)
			(layers "F.Cu" "F.Mask" "F.Paste")
			(net "PVDDCR_SOC_P1")
		)
		(pad "L19" smd circle
			(at -17.239996 -28.710128 180)
			(size 0.450088 0.450088)
			(layers "F.Cu" "F.Mask" "F.Paste")
			(net "M_I_CPU1_SA_DQ<8>")
		)
		(pad "L20" smd circle
			(at -16.299942 -28.710128 180)
			(size 0.450088 0.450088)
			(layers "F.Cu" "F.Mask" "F.Paste")
			(net "GND")
		)
		(pad "L21" smd circle
			(at -15.359888 -28.710128 180)
			(size 0.450088 0.450088)
			(layers "F.Cu" "F.Mask" "F.Paste")
			(net "M_I_CPU1_SA_DQ<7>")
		)
		(pad "L22" smd circle
			(at -14.420088 -28.710128 180)
			(size 0.450088 0.450088)
			(layers "F.Cu" "F.Mask" "F.Paste")
			(net "GND")
		)
		(pad "L23" smd circle
			(at -13.480034 -28.710128 180)
			(size 0.450088 0.450088)
			(layers "F.Cu" "F.Mask" "F.Paste")
			(net "GMI_CPU1_G2_CPU0_G0_TX_DP<12>")
		)
		(pad "L24" smd circle
			(at -12.53998 -28.710128 180)
			(size 0.450088 0.450088)
			(layers "F.Cu" "F.Mask" "F.Paste")
			(net "GMI_CPU1_G2_CPU0_G0_TX_DN<12>")
		)
		(pad "L25" smd circle
			(at -11.599926 -28.710128 180)
			(size 0.450088 0.450088)
			(layers "F.Cu" "F.Mask" "F.Paste")
			(net "GND")
		)
		(pad "L26" smd circle
			(at -10.659872 -28.710128 180)
			(size 0.450088 0.450088)
			(layers "F.Cu" "F.Mask" "F.Paste")
			(net "GMI_CPU1_G2_CPU0_G0_TX_DP<9>")
		)
		(pad "L27" smd circle
			(at -9.720072 -28.710128 180)
			(size 0.450088 0.450088)
			(layers "F.Cu" "F.Mask" "F.Paste")
			(net "GMI_CPU1_G2_CPU0_G0_TX_DN<9>")
		)
		(pad "L28" smd circle
			(at -8.780018 -28.710128 180)
			(size 0.450088 0.450088)
			(layers "F.Cu" "F.Mask" "F.Paste")
			(net "GND")
		)
		(pad "L29" smd circle
			(at -7.839964 -28.710128 180)
			(size 0.450088 0.450088)
			(layers "F.Cu" "F.Mask" "F.Paste")
			(net "GMI_CPU1_G2_CPU0_G0_TX_DP<6>")
		)
		(pad "L30" smd circle
			(at -6.89991 -28.710128 180)
			(size 0.450088 0.450088)
			(layers "F.Cu" "F.Mask" "F.Paste")
			(net "GMI_CPU1_G2_CPU0_G0_TX_DN<6>")
		)
		(pad "L31" smd circle
			(at -5.96011 -28.710128 180)
			(size 0.450088 0.450088)
			(layers "F.Cu" "F.Mask" "F.Paste")
			(net "GND")
		)
		(pad "L32" smd circle
			(at -5.020056 -28.710128 180)
			(size 0.450088 0.450088)
			(layers "F.Cu" "F.Mask" "F.Paste")
			(net "GMI_CPU1_G2_CPU0_G0_TX_DP<3>")
		)
		(pad "L33" smd circle
			(at -4.080002 -28.710128 180)
			(size 0.450088 0.450088)
			(layers "F.Cu" "F.Mask" "F.Paste")
			(net "GMI_CPU1_G2_CPU0_G0_TX_DN<3>")
		)
		(pad "L34" smd circle
			(at -3.139948 -28.710128 180)
			(size 0.450088 0.450088)
			(layers "F.Cu" "F.Mask" "F.Paste")
			(net "GND")
		)
		(pad "L35" smd circle
			(at -2.199894 -28.710128 180)
			(size 0.450088 0.450088)
			(layers "F.Cu" "F.Mask" "F.Paste")
			(net "GND")
		)
		(pad "L36" smd circle
			(at -1.260094 -28.710128 180)
			(size 0.450088 0.450088)
			(layers "F.Cu" "F.Mask" "F.Paste")
			(net "GND")
		)
		(pad "L40" smd circle
			(at 1.560068 -28.710128 180)
			(size 0.450088 0.450088)
			(layers "F.Cu" "F.Mask" "F.Paste")
			(net "GND")
		)
		(pad "L41" smd circle
			(at 2.500122 -28.710128 180)
			(size 0.450088 0.450088)
			(layers "F.Cu" "F.Mask" "F.Paste")
			(net "GND")
		)
		(pad "L42" smd circle
			(at 3.439922 -28.710128 180)
			(size 0.450088 0.450088)
			(layers "F.Cu" "F.Mask" "F.Paste")
			(net "GND")
		)
		(pad "L43" smd circle
			(at 4.379976 -28.710128 180)
			(size 0.450088 0.450088)
			(layers "F.Cu" "F.Mask" "F.Paste")
			(net "GMI_CPU0_G2_CPU1_G0_TX_DN<12>")
		)
		(pad "L44" smd circle
			(at 5.32003 -28.710128 180)
			(size 0.450088 0.450088)
			(layers "F.Cu" "F.Mask" "F.Paste")
			(net "GMI_CPU0_G2_CPU1_G0_TX_DP<12>")
		)
		(pad "L45" smd circle
			(at 6.260084 -28.710128 180)
			(size 0.450088 0.450088)
			(layers "F.Cu" "F.Mask" "F.Paste")
			(net "GND")
		)
		(pad "L46" smd circle
			(at 7.199884 -28.710128 180)
			(size 0.450088 0.450088)
			(layers "F.Cu" "F.Mask" "F.Paste")
			(net "GMI_CPU0_G2_CPU1_G0_TX_DN<9>")
		)
		(pad "L47" smd circle
			(at 8.139938 -28.710128 180)
			(size 0.450088 0.450088)
			(layers "F.Cu" "F.Mask" "F.Paste")
			(net "GMI_CPU0_G2_CPU1_G0_TX_DP<9>")
		)
		(pad "L48" smd circle
			(at 9.079992 -28.710128 180)
			(size 0.450088 0.450088)
			(layers "F.Cu" "F.Mask" "F.Paste")
			(net "GND")
		)
		(pad "L49" smd circle
			(at 10.020046 -28.710128 180)
			(size 0.450088 0.450088)
			(layers "F.Cu" "F.Mask" "F.Paste")
			(net "GMI_CPU0_G2_CPU1_G0_TX_DN<6>")
		)
		(pad "L50" smd circle
			(at 10.9601 -28.710128 180)
			(size 0.450088 0.450088)
			(layers "F.Cu" "F.Mask" "F.Paste")
			(net "GMI_CPU0_G2_CPU1_G0_TX_DP<6>")
		)
		(pad "L51" smd circle
			(at 11.8999 -28.710128 180)
			(size 0.450088 0.450088)
			(layers "F.Cu" "F.Mask" "F.Paste")
			(net "GND")
		)
		(pad "L52" smd circle
			(at 12.839954 -28.710128 180)
			(size 0.450088 0.450088)
			(layers "F.Cu" "F.Mask" "F.Paste")
			(net "GMI_CPU0_G2_CPU1_G0_TX_DN<3>")
		)
		(pad "L53" smd circle
			(at 13.780008 -28.710128 180)
			(size 0.450088 0.450088)
			(layers "F.Cu" "F.Mask" "F.Paste")
			(net "GMI_CPU0_G2_CPU1_G0_TX_DP<3>")
		)
		(pad "L54" smd circle
			(at 14.720062 -28.710128 180)
			(size 0.450088 0.450088)
			(layers "F.Cu" "F.Mask" "F.Paste")
			(net "GND")
		)
		(pad "L55" smd circle
			(at 15.660116 -28.710128 180)
			(size 0.450088 0.450088)
			(layers "F.Cu" "F.Mask" "F.Paste")
			(net "M_C_CPU1_SA_DQ<7>")
		)
		(pad "L56" smd circle
			(at 16.599916 -28.710128 180)
			(size 0.450088 0.450088)
			(layers "F.Cu" "F.Mask" "F.Paste")
			(net "GND")
		)
		(pad "L57" smd circle
			(at 17.53997 -28.710128 180)
			(size 0.450088 0.450088)
			(layers "F.Cu" "F.Mask" "F.Paste")
			(net "M_C_CPU1_SA_DQ<8>")
		)
		(pad "L58" smd circle
			(at 18.480024 -28.710128 180)
			(size 0.450088 0.450088)
			(layers "F.Cu" "F.Mask" "F.Paste")
			(net "PVDDIO_P1")
		)
		(pad "L59" smd circle
			(at 19.420078 -28.710128 180)
			(size 0.450088 0.450088)
			(layers "F.Cu" "F.Mask" "F.Paste")
			(net "M_D_CPU1_SA_DQ<7>")
		)
		(pad "L60" smd circle
			(at 20.359878 -28.710128 180)
			(size 0.450088 0.450088)
			(layers "F.Cu" "F.Mask" "F.Paste")
			(net "M_D_CPU1_SA_DQ<8>")
		)
		(pad "L61" smd circle
			(at 21.299932 -28.710128 180)
			(size 0.450088 0.450088)
			(layers "F.Cu" "F.Mask" "F.Paste")
			(net "GND")
		)
		(pad "L62" smd circle
			(at 22.239986 -28.710128 180)
			(size 0.450088 0.450088)
			(layers "F.Cu" "F.Mask" "F.Paste")
			(net "M_B_CPU1_SA_DQ<7>")
		)
		(pad "L63" smd circle
			(at 23.18004 -28.710128 180)
			(size 0.450088 0.450088)
			(layers "F.Cu" "F.Mask" "F.Paste")
			(net "GND")
		)
		(pad "L64" smd circle
			(at 24.120094 -28.710128 180)
			(size 0.450088 0.450088)
			(layers "F.Cu" "F.Mask" "F.Paste")
			(net "M_B_CPU1_SA_DQ<8>")
		)
		(pad "L65" smd circle
			(at 25.059894 -28.710128 180)
			(size 0.450088 0.450088)
			(layers "F.Cu" "F.Mask" "F.Paste")
			(net "PVDDIO_P1")
		)
		(pad "L66" smd circle
			(at 25.999948 -28.710128 180)
			(size 0.450088 0.450088)
			(layers "F.Cu" "F.Mask" "F.Paste")
			(net "M_F_CPU1_SA_DQ<7>")
		)
		(pad "L67" smd circle
			(at 26.940002 -28.710128 180)
			(size 0.450088 0.450088)
			(layers "F.Cu" "F.Mask" "F.Paste")
			(net "M_F_CPU1_SA_DQ<8>")
		)
		(pad "L68" smd circle
			(at 27.880056 -28.710128 180)
			(size 0.450088 0.450088)
			(layers "F.Cu" "F.Mask" "F.Paste")
			(net "GND")
		)
		(pad "L69" smd circle
			(at 28.82011 -28.710128 180)
			(size 0.450088 0.450088)
			(layers "F.Cu" "F.Mask" "F.Paste")
			(net "M_E_CPU1_SA_DQ<7>")
		)
		(pad "L70" smd circle
			(at 29.75991 -28.710128 180)
			(size 0.450088 0.450088)
			(layers "F.Cu" "F.Mask" "F.Paste")
			(net "GND")
		)
		(pad "L71" smd circle
			(at 30.699964 -28.710128 180)
			(size 0.450088 0.450088)
			(layers "F.Cu" "F.Mask" "F.Paste")
			(net "M_E_CPU1_SA_DQ<8>")
		)
	)
)
